#ISCELL
  pure_quanta quanta_title_block_c *
  *
#ISCELL
  standard offpage *
  page193_i1
#CELL
  pure_quanta q_res *
  page193_i10
#ISCELL
  standard offpage *
  page193_i12
#CELL
  pure_quanta q_res *
  page193_i13
#ISCELL
  standard offpage *
  page193_i14
#ISCELL
  standard offpage *
  page193_i18
#ISCELL
  standard offpage *
  page193_i19
#ISCELL
  standard offpage *
  page193_i2
#CELL
  pure_quanta q_res *
  page193_i20
#CELL
  pure_quanta q_res *
  page193_i21
#ISCELL
  standard offpage *
  page193_i22
#ISCELL
  standard offpage *
  page193_i23
#ISCELL
  standard offpage *
  page193_i25
#ISCELL
  standard offpage *
  page193_i26
#CELL
  pure_quanta q_res *
  page193_i27
#CELL
  pure_quanta q_res *
  page193_i28
#ISCELL
  standard offpage *
  page193_i29
#CELL
  pure_quanta q_res *
  page193_i3
#ISCELL
  standard offpage *
  page193_i30
#CELL
  pure_quanta q_res *
  page193_i32
#ISCELL
  standard offpage *
  page193_i36
#ISCELL
  standard offpage *
  page193_i37
#ISCELL
  standard offpage *
  page193_i38
#ISCELL
  standard offpage *
  page193_i39
#ISCELL
  standard offpage *
  page193_i4
#CELL
  pure_quanta q_res *
  page193_i40
#ISCELL
  standard offpage *
  page193_i41
#CELL
  pure_quanta q_res *
  page193_i5
#ISCELL
  standard offpage *
  page193_i6
